# S9S_MB_2U (Grand Teton) — schematic netlist excerpt (pin names and nets, part order shuffled) for the footprints in the layout excerpt that follows; sources: Cadence DE-HDL packaged netlist, KiCad conversion of 03242023_DA0F0TMBIJ0_F0T_Motherboard_J_brd_V01_OCP.brd

PR4237  Q_RES  499 1% CHIP  pkg 0402LF  page 279 : A = PVCCD_HV_CPU0 ; B = GND
C1022  Q_CAP  22UF 4V 20% X6S  pkg C0402  page 74 : A = PVCCIN_CPU0 ; B = GND

(kicad_pcb
	(version 20260206)
	(generator "pcbnew")
	(generator_version "10.0")
	(general
		(thickness 1.6)
		(legacy_teardrops no)
	)
	(paper "A4")
	(title_block
		(title "03242023_DA0F0TMBIJ0_F0T_Motherboard_J_brd_V01_OCP.brd")
		(comment 1 "Grand Teton / footprints 1381-1382 of 6105")
	)
	(layers
		(0 "F.Cu" signal "TOP")
		(4 "In1.Cu" signal "GND")
		(6 "In2.Cu" signal "IN1")
		(8 "In3.Cu" signal "GND1")
		(10 "In4.Cu" signal "IN2")
		(12 "In5.Cu" signal "GND2")
		(14 "In6.Cu" signal "IN3")
		(16 "In7.Cu" signal "GND3")
		(18 "In8.Cu" signal "VCC")
		(20 "In9.Cu" signal "VCC1")
		(22 "In10.Cu" signal "GND4")
		(24 "In11.Cu" signal "IN4")
		(26 "In12.Cu" signal "GND5")
		(28 "In13.Cu" signal "IN5")
		(30 "In14.Cu" signal "GND6")
		(32 "In15.Cu" signal "IN6")
		(34 "In16.Cu" signal "GND7")
		(2 "B.Cu" signal "BOTTOM")
		(9 "F.Adhes" user "F.Adhesive")
		(11 "B.Adhes" user "B.Adhesive")
		(13 "F.Paste" user "Package Geometry/Pastemask Top")
		(15 "B.Paste" user "Package Geometry/Pastemask Bottom")
		(5 "F.SilkS" user "Ref Des/Silkscreen Top")
		(7 "B.SilkS" user "Ref Des/Silkscreen Bottom")
		(1 "F.Mask" user "Board Geometry/Soldermask Top")
		(3 "B.Mask" user "Board Geometry/Soldermask Bottom")
		(17 "Dwgs.User" user "User.Drawings")
		(19 "Cmts.User" user "User.Comments")
		(21 "Eco1.User" user "User.Eco1")
		(23 "Eco2.User" user "User.Eco2")
		(25 "Edge.Cuts" user "Board Geometry/Outline")
		(27 "Margin" user)
		(31 "F.CrtYd" user "Package Geometry/Place Bound Top")
		(29 "B.CrtYd" user "Package Geometry/Place Bound Bottom")
		(35 "F.Fab" user "Ref Des/Assembly Top")
		(33 "B.Fab" user "Ref Des/Assembly Bottom")
	)
	(footprint ""
		(layer "F.Cu")
		(at 396.822168 -165.363906 180)
		(property "Reference" "PR4237"
			(at 0 0 180)
			(layer "F.SilkS")
			(hide yes)
			(effects
				(font
					(size 1.27 1.27)
				)
			)
		)
		(property "Value" ""
			(at 0 0 180)
			(layer "F.Fab")
			(effects
				(font
					(size 1.27 1.27)
				)
			)
		)
		(duplicate_pad_numbers_are_jumpers no)
		(fp_line
			(start 0.7874 0.4064)
			(end -0.7874 0.4064)
			(stroke
				(width 0.1524)
				(type default)
			)
			(layer "F.SilkS")
		)
		(fp_line
			(start 0.7874 -0.4064)
			(end 0.7874 0.4064)
			(stroke
				(width 0.1524)
				(type default)
			)
			(layer "F.SilkS")
		)
		(fp_line
			(start -0.7874 0.4064)
			(end -0.7874 -0.4064)
			(stroke
				(width 0.1524)
				(type default)
			)
			(layer "F.SilkS")
		)
		(fp_line
			(start -0.7874 -0.4064)
			(end 0.7874 -0.4064)
			(stroke
				(width 0.1524)
				(type default)
			)
			(layer "F.SilkS")
		)
		(fp_line
			(start 0.67945 0.3048)
			(end 0.120396 0.3048)
			(stroke
				(width 0.1)
				(type default)
			)
			(layer "F.Fab")
		)
		(fp_line
			(start 0.67945 -0.3048)
			(end 0.67945 0.3048)
			(stroke
				(width 0.1)
				(type default)
			)
			(layer "F.Fab")
		)
		(fp_line
			(start 0.12065 -0.2794)
			(end 0.12065 -0.3048)
			(stroke
				(width 0.1)
				(type default)
			)
			(layer "F.Fab")
		)
		(fp_line
			(start 0.12065 -0.3048)
			(end 0.67945 -0.3048)
			(stroke
				(width 0.1)
				(type default)
			)
			(layer "F.Fab")
		)
		(fp_line
			(start 0.120396 0.3048)
			(end 0.120396 0.2794)
			(stroke
				(width 0.1)
				(type default)
			)
			(layer "F.Fab")
		)
		(fp_line
			(start 0.120396 0.2794)
			(end -0.12065 0.2794)
			(stroke
				(width 0.1)
				(type default)
			)
			(layer "F.Fab")
		)
		(fp_line
			(start -0.12065 0.3048)
			(end -0.67945 0.3048)
			(stroke
				(width 0.1)
				(type default)
			)
			(layer "F.Fab")
		)
		(fp_line
			(start -0.12065 0.2794)
			(end -0.12065 0.3048)
			(stroke
				(width 0.1)
				(type default)
			)
			(layer "F.Fab")
		)
		(fp_line
			(start -0.12065 -0.2794)
			(end 0.12065 -0.2794)
			(stroke
				(width 0.1)
				(type default)
			)
			(layer "F.Fab")
		)
		(fp_line
			(start -0.12065 -0.305054)
			(end -0.12065 -0.2794)
			(stroke
				(width 0.1)
				(type default)
			)
			(layer "F.Fab")
		)
		(fp_line
			(start -0.67945 0.3048)
			(end -0.67945 -0.305054)
			(stroke
				(width 0.1)
				(type default)
			)
			(layer "F.Fab")
		)
		(fp_line
			(start -0.67945 -0.305054)
			(end -0.12065 -0.305054)
			(stroke
				(width 0.1)
				(type default)
			)
			(layer "F.Fab")
		)
		(pad "1" smd circle
			(at -0.40005 0 180)
			(size 0 0)
			(layers "F.Cu" "F.Mask" "F.Paste")
			(net "PVCCD_HV_CPU0")
		)
		(pad "2" smd circle
			(at 0.40005 0 180)
			(size 0 0)
			(layers "F.Cu" "F.Mask" "F.Paste")
			(net "GND")
		)
	)
	(footprint ""
		(layer "F.Cu")
		(at 354.264214 -251.375418 90)
		(property "Reference" "C1022"
			(at 0 0 90)
			(layer "F.SilkS")
			(hide yes)
			(effects
				(font
					(size 1.27 1.27)
				)
			)
		)
		(property "Value" ""
			(at 0 0 90)
			(layer "F.Fab")
			(effects
				(font
					(size 1.27 1.27)
				)
			)
		)
		(duplicate_pad_numbers_are_jumpers no)
		(fp_line
			(start 0.7874 -0.4064)
			(end 0.7874 0.4064)
			(stroke
				(width 0.1524)
				(type default)
			)
			(layer "F.SilkS")
		)
		(fp_line
			(start -0.7874 -0.4064)
			(end 0.7874 -0.4064)
			(stroke
				(width 0.1524)
				(type default)
			)
			(layer "F.SilkS")
		)
		(fp_line
			(start 0.7874 0.4064)
			(end -0.7874 0.4064)
			(stroke
				(width 0.1524)
				(type default)
			)
			(layer "F.SilkS")
		)
		(fp_line
			(start -0.7874 0.4064)
			(end -0.7874 -0.4064)
			(stroke
				(width 0.1524)
				(type default)
			)
			(layer "F.SilkS")
		)
		(fp_line
			(start -0.12065 -0.305054)
			(end -0.12065 -0.2794)
			(stroke
				(width 0.1)
				(type default)
			)
			(layer "F.Fab")
		)
		(fp_line
			(start -0.67945 -0.305054)
			(end -0.12065 -0.305054)
			(stroke
				(width 0.1)
				(type default)
			)
			(layer "F.Fab")
		)
		(fp_line
			(start 0.67945 -0.3048)
			(end 0.67945 0.3048)
			(stroke
				(width 0.1)
				(type default)
			)
			(layer "F.Fab")
		)
		(fp_line
			(start 0.12065 -0.3048)
			(end 0.67945 -0.3048)
			(stroke
				(width 0.1)
				(type default)
			)
			(layer "F.Fab")
		)
		(fp_line
			(start 0.12065 -0.2794)
			(end 0.12065 -0.3048)
			(stroke
				(width 0.1)
				(type default)
			)
			(layer "F.Fab")
		)
		(fp_line
			(start -0.12065 -0.2794)
			(end 0.12065 -0.2794)
			(stroke
				(width 0.1)
				(type default)
			)
			(layer "F.Fab")
		)
		(fp_line
			(start 0.120396 0.2794)
			(end -0.12065 0.2794)
			(stroke
				(width 0.1)
				(type default)
			)
			(layer "F.Fab")
		)
		(fp_line
			(start -0.12065 0.2794)
			(end -0.12065 0.3048)
			(stroke
				(width 0.1)
				(type default)
			)
			(layer "F.Fab")
		)
		(fp_line
			(start 0.67945 0.3048)
			(end 0.120396 0.3048)
			(stroke
				(width 0.1)
				(type default)
			)
			(layer "F.Fab")
		)
		(fp_line
			(start 0.120396 0.3048)
			(end 0.120396 0.2794)
			(stroke
				(width 0.1)
				(type default)
			)
			(layer "F.Fab")
		)
		(fp_line
			(start -0.12065 0.3048)
			(end -0.67945 0.3048)
			(stroke
				(width 0.1)
				(type default)
			)
			(layer "F.Fab")
		)
		(fp_line
			(start -0.67945 0.3048)
			(end -0.67945 -0.305054)
			(stroke
				(width 0.1)
				(type default)
			)
			(layer "F.Fab")
		)
		(pad "1" smd circle
			(at -0.40005 0 90)
			(size 0 0)
			(layers "F.Cu" "F.Mask" "F.Paste")
			(net "PVCCIN_CPU0")
		)
		(pad "2" smd circle
			(at 0.40005 0 90)
			(size 0 0)
			(layers "F.Cu" "F.Mask" "F.Paste")
			(net "GND")
		)
	)
)
